(kicad_pcb
	(version 20241229)
	(generator "pcbnew")
	(generator_version "9.0")
	(general
		(thickness 1.61)
		(legacy_teardrops no)
	)
	(paper "A3")
	(title_block
		(title "SO-DIMM DDR5 Tester")
		(date "2025-11-26")
		(rev "1.3.0")
		(comment 9 "footprints 8-14 of 627")
	)
	(layers
		(0 "F.Cu" signal)
		(4 "In1.Cu" power)
		(6 "In2.Cu" mixed)
		(8 "In3.Cu" power)
		(10 "In4.Cu" mixed)
		(12 "In5.Cu" power)
		(14 "In6.Cu" mixed)
		(16 "In7.Cu" power)
		(18 "In8.Cu" power)
		(20 "In9.Cu" mixed)
		(22 "In10.Cu" power)
		(2 "B.Cu" signal)
		(9 "F.Adhes" user "F.Adhesive")
		(11 "B.Adhes" user "B.Adhesive")
		(13 "F.Paste" user)
		(15 "B.Paste" user)
		(5 "F.SilkS" user "F.Silkscreen")
		(7 "B.SilkS" user "B.Silkscreen")
		(1 "F.Mask" user)
		(3 "B.Mask" user)
		(17 "Dwgs.User" user "User.Drawings")
		(19 "Cmts.User" user "User.Comments")
		(21 "Eco1.User" user "User.Eco1")
		(23 "Eco2.User" user "User.Eco2")
		(25 "Edge.Cuts" user)
		(27 "Margin" user)
		(31 "F.CrtYd" user "F.Courtyard")
		(29 "B.CrtYd" user "B.Courtyard")
		(35 "F.Fab" user)
		(33 "B.Fab" user)
	)
	(footprint "antmicro-footprints:R_0402_1005Metric"
		(layer "F.Cu")
		(at 94.5 184.6 -90)
		(descr "Resistor SMD 0402")
		(tags "resistor SMD 0402")
		(property "Reference" "R48"
			(at -1.122484 -0.772697 270)
			(layer "F.SilkS")
			(hide yes)
			(effects
				(font
					(size 0.7 0.7)
					(thickness 0.15)
				)
				(justify left bottom)
			)
		)
		(property "Value" "R_22R_0402"
			(at -1.011843 1.772047 270)
			(layer "F.Fab")
			(effects
				(font
					(size 0.7 0.7)
					(thickness 0.15)
				)
				(justify left bottom)
			)
		)
		(property "Datasheet" "https://www.bourns.com/docs/product-datasheets/cr.pdf"
			(at 0 0 270)
			(layer "F.Fab")
			(hide yes)
			(effects
				(font
					(size 1.27 1.27)
					(thickness 0.15)
				)
			)
		)
		(property "Author" "Antmicro"
			(at -90.1 279.1 0)
			(layer "F.Fab")
			(hide yes)
			(effects
				(font
					(size 1 1)
					(thickness 0.15)
				)
			)
		)
		(property "License" "Apache-2.0"
			(at -90.1 279.1 0)
			(layer "F.Fab")
			(hide yes)
			(effects
				(font
					(size 1 1)
					(thickness 0.15)
				)
			)
		)
		(property "MPN" "CR0402-FX-22R0GLF"
			(at -90.1 279.1 0)
			(layer "F.Fab")
			(hide yes)
			(effects
				(font
					(size 1 1)
					(thickness 0.15)
				)
			)
		)
		(property "Manufacturer" "Bourns"
			(at -90.1 279.1 0)
			(layer "F.Fab")
			(hide yes)
			(effects
				(font
					(size 1 1)
					(thickness 0.15)
				)
			)
		)
		(property "Tolerance" "1%"
			(at -90.1 279.1 0)
			(layer "F.Fab")
			(hide yes)
			(effects
				(font
					(size 1 1)
					(thickness 0.15)
				)
			)
		)
		(property "Val" "22R"
			(at -90.1 279.1 0)
			(layer "F.Fab")
			(hide yes)
			(effects
				(font
					(size 1 1)
					(thickness 0.15)
				)
			)
		)
		(sheetname "/Debug FTDI/")
		(sheetfile "debug-ftdi.kicad_sch")
		(attr smd)
		(fp_rect
			(start -0.93 -0.47)
			(end 0.93 0.47)
			(stroke
				(width 0.05)
				(type solid)
			)
			(fill no)
			(layer "F.CrtYd")
		)
		(fp_rect
			(start -0.5 -0.25)
			(end 0.5 0.25)
			(stroke
				(width 0.15)
				(type solid)
			)
			(fill no)
			(layer "F.Fab")
		)
		(pad "1" smd roundrect
			(at -0.485 0 270)
			(size 0.59 0.64)
			(layers "F.Cu" "F.Mask" "F.Paste")
			(roundrect_rratio 0.25)
			(net 380 "Net-(U7-B2Y)")
			(pintype "passive")
		)
		(pad "2" smd roundrect
			(at 0.485 0 270)
			(size 0.59 0.64)
			(layers "F.Cu" "F.Mask" "F.Paste")
			(roundrect_rratio 0.25)
			(net 46 "/Debug FTDI/JTAG.TCK")
			(pintype "passive")
		)
	)
	(footprint "antmicro-footprints:R_0402_1005Metric"
		(layer "F.Cu")
		(at 92.3 184.6 -90)
		(descr "Resistor SMD 0402")
		(tags "resistor SMD 0402")
		(property "Reference" "R50"
			(at -1.122484 -0.772697 270)
			(layer "F.SilkS")
			(hide yes)
			(effects
				(font
					(size 0.7 0.7)
					(thickness 0.15)
				)
				(justify left bottom)
			)
		)
		(property "Value" "R_22R_0402"
			(at -1.011843 1.772047 270)
			(layer "F.Fab")
			(effects
				(font
					(size 0.7 0.7)
					(thickness 0.15)
				)
				(justify left bottom)
			)
		)
		(property "Datasheet" "https://www.bourns.com/docs/product-datasheets/cr.pdf"
			(at 0 0 270)
			(layer "F.Fab")
			(hide yes)
			(effects
				(font
					(size 1.27 1.27)
					(thickness 0.15)
				)
			)
		)
		(property "Author" "Antmicro"
			(at -92.3 276.9 0)
			(layer "F.Fab")
			(hide yes)
			(effects
				(font
					(size 1 1)
					(thickness 0.15)
				)
			)
		)
		(property "License" "Apache-2.0"
			(at -92.3 276.9 0)
			(layer "F.Fab")
			(hide yes)
			(effects
				(font
					(size 1 1)
					(thickness 0.15)
				)
			)
		)
		(property "MPN" "CR0402-FX-22R0GLF"
			(at -92.3 276.9 0)
			(layer "F.Fab")
			(hide yes)
			(effects
				(font
					(size 1 1)
					(thickness 0.15)
				)
			)
		)
		(property "Manufacturer" "Bourns"
			(at -92.3 276.9 0)
			(layer "F.Fab")
			(hide yes)
			(effects
				(font
					(size 1 1)
					(thickness 0.15)
				)
			)
		)
		(property "Tolerance" "1%"
			(at -92.3 276.9 0)
			(layer "F.Fab")
			(hide yes)
			(effects
				(font
					(size 1 1)
					(thickness 0.15)
				)
			)
		)
		(property "Val" "22R"
			(at -92.3 276.9 0)
			(layer "F.Fab")
			(hide yes)
			(effects
				(font
					(size 1 1)
					(thickness 0.15)
				)
			)
		)
		(sheetname "/Debug FTDI/")
		(sheetfile "debug-ftdi.kicad_sch")
		(attr smd)
		(fp_rect
			(start -0.93 -0.47)
			(end 0.93 0.47)
			(stroke
				(width 0.05)
				(type solid)
			)
			(fill no)
			(layer "F.CrtYd")
		)
		(fp_rect
			(start -0.5 -0.25)
			(end 0.5 0.25)
			(stroke
				(width 0.15)
				(type solid)
			)
			(fill no)
			(layer "F.Fab")
		)
		(pad "1" smd roundrect
			(at -0.485 0 270)
			(size 0.59 0.64)
			(layers "F.Cu" "F.Mask" "F.Paste")
			(roundrect_rratio 0.25)
			(net 382 "Net-(U7-B4)")
			(pintype "passive")
		)
		(pad "2" smd roundrect
			(at 0.485 0 270)
			(size 0.59 0.64)
			(layers "F.Cu" "F.Mask" "F.Paste")
			(roundrect_rratio 0.25)
			(net 47 "/Debug FTDI/JTAG.TDO")
			(pintype "passive")
		)
	)
	(footprint "antmicro-footprints:R_0402_1005Metric"
		(layer "F.Cu")
		(at 93.422843 184.598328 -90)
		(descr "Resistor SMD 0402")
		(tags "resistor SMD 0402")
		(property "Reference" "R49"
			(at -1.122484 -0.772697 270)
			(layer "F.SilkS")
			(hide yes)
			(effects
				(font
					(size 0.7 0.7)
					(thickness 0.15)
				)
				(justify left bottom)
			)
		)
		(property "Value" "R_22R_0402"
			(at -1.011843 1.772047 270)
			(layer "F.Fab")
			(effects
				(font
					(size 0.7 0.7)
					(thickness 0.15)
				)
				(justify left bottom)
			)
		)
		(property "Datasheet" "https://www.bourns.com/docs/product-datasheets/cr.pdf"
			(at 0 0 270)
			(layer "F.Fab")
			(hide yes)
			(effects
				(font
					(size 1.27 1.27)
					(thickness 0.15)
				)
			)
		)
		(property "Author" "Antmicro"
			(at -91.175485 278.021171 0)
			(layer "F.Fab")
			(hide yes)
			(effects
				(font
					(size 1 1)
					(thickness 0.15)
				)
			)
		)
		(property "License" "Apache-2.0"
			(at -91.175485 278.021171 0)
			(layer "F.Fab")
			(hide yes)
			(effects
				(font
					(size 1 1)
					(thickness 0.15)
				)
			)
		)
		(property "MPN" "CR0402-FX-22R0GLF"
			(at -91.175485 278.021171 0)
			(layer "F.Fab")
			(hide yes)
			(effects
				(font
					(size 1 1)
					(thickness 0.15)
				)
			)
		)
		(property "Manufacturer" "Bourns"
			(at -91.175485 278.021171 0)
			(layer "F.Fab")
			(hide yes)
			(effects
				(font
					(size 1 1)
					(thickness 0.15)
				)
			)
		)
		(property "Tolerance" "1%"
			(at -91.175485 278.021171 0)
			(layer "F.Fab")
			(hide yes)
			(effects
				(font
					(size 1 1)
					(thickness 0.15)
				)
			)
		)
		(property "Val" "22R"
			(at -91.175485 278.021171 0)
			(layer "F.Fab")
			(hide yes)
			(effects
				(font
					(size 1 1)
					(thickness 0.15)
				)
			)
		)
		(sheetname "/Debug FTDI/")
		(sheetfile "debug-ftdi.kicad_sch")
		(attr smd)
		(fp_rect
			(start -0.93 -0.47)
			(end 0.93 0.47)
			(stroke
				(width 0.05)
				(type solid)
			)
			(fill no)
			(layer "F.CrtYd")
		)
		(fp_rect
			(start -0.5 -0.25)
			(end 0.5 0.25)
			(stroke
				(width 0.15)
				(type solid)
			)
			(fill no)
			(layer "F.Fab")
		)
		(pad "1" smd roundrect
			(at -0.485 0 270)
			(size 0.59 0.64)
			(layers "F.Cu" "F.Mask" "F.Paste")
			(roundrect_rratio 0.25)
			(net 381 "Net-(U7-B3Y)")
			(pintype "passive")
		)
		(pad "2" smd roundrect
			(at 0.485 0 270)
			(size 0.59 0.64)
			(layers "F.Cu" "F.Mask" "F.Paste")
			(roundrect_rratio 0.25)
			(net 48 "/Debug FTDI/JTAG.TDI")
			(pintype "passive")
		)
	)
	(footprint "antmicro-footprints:R_0402_1005Metric"
		(layer "F.Cu")
		(at 95.6 184.6 -90)
		(descr "Resistor SMD 0402")
		(tags "resistor SMD 0402")
		(property "Reference" "R47"
			(at -1.122484 -0.772697 270)
			(layer "F.SilkS")
			(hide yes)
			(effects
				(font
					(size 0.7 0.7)
					(thickness 0.15)
				)
				(justify left bottom)
			)
		)
		(property "Value" "R_22R_0402"
			(at -1.011843 1.772047 270)
			(layer "F.Fab")
			(effects
				(font
					(size 0.7 0.7)
					(thickness 0.15)
				)
				(justify left bottom)
			)
		)
		(property "Datasheet" "https://www.bourns.com/docs/product-datasheets/cr.pdf"
			(at 0 0 270)
			(layer "F.Fab")
			(hide yes)
			(effects
				(font
					(size 1.27 1.27)
					(thickness 0.15)
				)
			)
		)
		(property "Author" "Antmicro"
			(at -89 280.2 0)
			(layer "F.Fab")
			(hide yes)
			(effects
				(font
					(size 1 1)
					(thickness 0.15)
				)
			)
		)
		(property "License" "Apache-2.0"
			(at -89 280.2 0)
			(layer "F.Fab")
			(hide yes)
			(effects
				(font
					(size 1 1)
					(thickness 0.15)
				)
			)
		)
		(property "MPN" "CR0402-FX-22R0GLF"
			(at -89 280.2 0)
			(layer "F.Fab")
			(hide yes)
			(effects
				(font
					(size 1 1)
					(thickness 0.15)
				)
			)
		)
		(property "Manufacturer" "Bourns"
			(at -89 280.2 0)
			(layer "F.Fab")
			(hide yes)
			(effects
				(font
					(size 1 1)
					(thickness 0.15)
				)
			)
		)
		(property "Tolerance" "1%"
			(at -89 280.2 0)
			(layer "F.Fab")
			(hide yes)
			(effects
				(font
					(size 1 1)
					(thickness 0.15)
				)
			)
		)
		(property "Val" "22R"
			(at -89 280.2 0)
			(layer "F.Fab")
			(hide yes)
			(effects
				(font
					(size 1 1)
					(thickness 0.15)
				)
			)
		)
		(sheetname "/Debug FTDI/")
		(sheetfile "debug-ftdi.kicad_sch")
		(attr smd)
		(fp_rect
			(start -0.93 -0.47)
			(end 0.93 0.47)
			(stroke
				(width 0.05)
				(type solid)
			)
			(fill no)
			(layer "F.CrtYd")
		)
		(fp_rect
			(start -0.5 -0.25)
			(end 0.5 0.25)
			(stroke
				(width 0.15)
				(type solid)
			)
			(fill no)
			(layer "F.Fab")
		)
		(pad "1" smd roundrect
			(at -0.485 0 270)
			(size 0.59 0.64)
			(layers "F.Cu" "F.Mask" "F.Paste")
			(roundrect_rratio 0.25)
			(net 378 "Net-(U7-B1Y)")
			(pintype "passive")
		)
		(pad "2" smd roundrect
			(at 0.485 0 270)
			(size 0.59 0.64)
			(layers "F.Cu" "F.Mask" "F.Paste")
			(roundrect_rratio 0.25)
			(net 45 "/Debug FTDI/JTAG.TMS")
			(pintype "passive")
		)
	)
	(footprint "antmicro-footprints:C_0402_1005Metric"
		(layer "F.Cu")
		(at 97.272344 167.552328 90)
		(descr "Capacitor SMD 0402")
		(tags "capacitor SMD 0402")
		(property "Reference" "C115"
			(at 0 -0.699 90)
			(layer "F.SilkS")
			(hide yes)
			(effects
				(font
					(size 0.7 0.7)
					(thickness 0.15)
				)
				(justify left bottom)
			)
		)
		(property "Value" "C_100n_0402"
			(at -1.022927 2.155213 90)
			(layer "F.Fab")
			(effects
				(font
					(size 0.7 0.7)
					(thickness 0.15)
				)
				(justify left bottom)
			)
		)
		(property "Datasheet" "https://www.murata.com/products/productdetail?partno=GRM155R61H104KE14%23"
			(at 0 0 90)
			(layer "F.Fab")
			(hide yes)
			(effects
				(font
					(size 1.27 1.27)
					(thickness 0.15)
				)
			)
		)
		(property "Author" "Antmicro"
			(at 264.824672 70.279984 0)
			(layer "F.Fab")
			(hide yes)
			(effects
				(font
					(size 1 1)
					(thickness 0.15)
				)
			)
		)
		(property "Dielectric" "X5R"
			(at 264.824672 70.279984 0)
			(layer "F.Fab")
			(hide yes)
			(effects
				(font
					(size 1 1)
					(thickness 0.15)
				)
			)
		)
		(property "License" "Apache-2.0"
			(at 264.824672 70.279984 0)
			(layer "F.Fab")
			(hide yes)
			(effects
				(font
					(size 1 1)
					(thickness 0.15)
				)
			)
		)
		(property "MPN" "GRM155R61H104KE14D"
			(at 264.824672 70.279984 0)
			(layer "F.Fab")
			(hide yes)
			(effects
				(font
					(size 1 1)
					(thickness 0.15)
				)
			)
		)
		(property "Manufacturer" "Murata"
			(at 264.824672 70.279984 0)
			(layer "F.Fab")
			(hide yes)
			(effects
				(font
					(size 1 1)
					(thickness 0.15)
				)
			)
		)
		(property "Val" "100n"
			(at 264.824672 70.279984 0)
			(layer "F.Fab")
			(hide yes)
			(effects
				(font
					(size 1 1)
					(thickness 0.15)
				)
			)
		)
		(property "Voltage" "50V"
			(at 264.824672 70.279984 0)
			(layer "F.Fab")
			(hide yes)
			(effects
				(font
					(size 1 1)
					(thickness 0.15)
				)
			)
		)
		(sheetname "/Debug FTDI/")
		(sheetfile "debug-ftdi.kicad_sch")
		(attr smd)
		(fp_rect
			(start -0.9659 -0.481258)
			(end 0.9649 0.458742)
			(stroke
				(width 0.05)
				(type solid)
			)
			(fill no)
			(layer "F.CrtYd")
		)
		(fp_line
			(start 0.499 -0.25)
			(end 0.499 0.248)
			(stroke
				(width 0.15)
				(type solid)
			)
			(layer "F.Fab")
		)
		(fp_line
			(start -0.499 -0.25)
			(end 0.499 -0.25)
			(stroke
				(width 0.15)
				(type solid)
			)
			(layer "F.Fab")
		)
		(fp_line
			(start 0.499 0.248)
			(end -0.499 0.248)
			(stroke
				(width 0.15)
				(type solid)
			)
			(layer "F.Fab")
		)
		(fp_line
			(start -0.499 0.248)
			(end -0.499 -0.25)
			(stroke
				(width 0.15)
				(type solid)
			)
			(layer "F.Fab")
		)
		(pad "1" smd roundrect
			(at -0.484 0 90)
			(size 0.59 0.64)
			(layers "F.Cu" "F.Mask" "F.Paste")
			(roundrect_rratio 0.25)
			(net 6 "/Debug FTDI/FTDI_3V3")
			(pintype "passive")
		)
		(pad "2" smd roundrect
			(at 0.484 0 90)
			(size 0.59 0.64)
			(layers "F.Cu" "F.Mask" "F.Paste")
			(roundrect_rratio 0.25)
			(net 1 "GND")
			(pintype "passive")
		)
	)
	(footprint "antmicro-footprints:C_0402_1005Metric"
		(layer "F.Cu")
		(at 94.059829 167.547157 90)
		(descr "Capacitor SMD 0402")
		(tags "capacitor SMD 0402")
		(property "Reference" "C111"
			(at 0 -0.699 90)
			(layer "F.SilkS")
			(hide yes)
			(effects
				(font
					(size 0.7 0.7)
					(thickness 0.15)
				)
				(justify left bottom)
			)
		)
		(property "Value" "C_18p_0402"
			(at -1.022927 2.155213 90)
			(layer "F.Fab")
			(effects
				(font
					(size 0.7 0.7)
					(thickness 0.15)
				)
				(justify left bottom)
			)
		)
		(property "Datasheet" "https://product.samsungsem.com/mlcc/CL05C180JB51PN.do"
			(at 0 0 90)
			(layer "F.Fab")
			(hide yes)
			(effects
				(font
					(size 1.27 1.27)
					(thickness 0.15)
				)
			)
		)
		(property "Author" "Antmicro"
			(at 261.606986 73.487328 0)
			(layer "F.Fab")
			(hide yes)
			(effects
				(font
					(size 1 1)
					(thickness 0.15)
				)
			)
		)
		(property "Dielectric" ""
			(at 261.606986 73.487328 0)
			(layer "F.Fab")
			(hide yes)
			(effects
				(font
					(size 1 1)
					(thickness 0.15)
				)
			)
		)
		(property "License" "Apache-2.0"
			(at 261.606986 73.487328 0)
			(layer "F.Fab")
			(hide yes)
			(effects
				(font
					(size 1 1)
					(thickness 0.15)
				)
			)
		)
		(property "MPN" "CL05C180JB51PNC"
			(at 261.606986 73.487328 0)
			(layer "F.Fab")
			(hide yes)
			(effects
				(font
					(size 1 1)
					(thickness 0.15)
				)
			)
		)
		(property "Manufacturer" "Samsung Electro-Mechanics"
			(at 261.606986 73.487328 0)
			(layer "F.Fab")
			(hide yes)
			(effects
				(font
					(size 1 1)
					(thickness 0.15)
				)
			)
		)
		(property "Val" "18p"
			(at 261.606986 73.487328 0)
			(layer "F.Fab")
			(hide yes)
			(effects
				(font
					(size 1 1)
					(thickness 0.15)
				)
			)
		)
		(property "Voltage" ""
			(at 261.606986 73.487328 0)
			(layer "F.Fab")
			(hide yes)
			(effects
				(font
					(size 1 1)
					(thickness 0.15)
				)
			)
		)
		(sheetname "/Debug FTDI/")
		(sheetfile "debug-ftdi.kicad_sch")
		(attr smd)
		(fp_rect
			(start -0.9659 -0.481258)
			(end 0.9649 0.458742)
			(stroke
				(width 0.05)
				(type solid)
			)
			(fill no)
			(layer "F.CrtYd")
		)
		(fp_line
			(start 0.499 -0.25)
			(end 0.499 0.248)
			(stroke
				(width 0.15)
				(type solid)
			)
			(layer "F.Fab")
		)
		(fp_line
			(start -0.499 -0.25)
			(end 0.499 -0.25)
			(stroke
				(width 0.15)
				(type solid)
			)
			(layer "F.Fab")
		)
		(fp_line
			(start 0.499 0.248)
			(end -0.499 0.248)
			(stroke
				(width 0.15)
				(type solid)
			)
			(layer "F.Fab")
		)
		(fp_line
			(start -0.499 0.248)
			(end -0.499 -0.25)
			(stroke
				(width 0.15)
				(type solid)
			)
			(layer "F.Fab")
		)
		(pad "1" smd roundrect
			(at -0.484 0 90)
			(size 0.59 0.64)
			(layers "F.Cu" "F.Mask" "F.Paste")
			(roundrect_rratio 0.25)
			(net 4 "/Debug FTDI/FTDI_XI")
			(pintype "passive")
		)
		(pad "2" smd roundrect
			(at 0.484 0 90)
			(size 0.59 0.64)
			(layers "F.Cu" "F.Mask" "F.Paste")
			(roundrect_rratio 0.25)
			(net 1 "GND")
			(pintype "passive")
		)
	)
	(footprint "antmicro-footprints:C_0402_1005Metric"
		(layer "F.Cu")
		(at 97.9 180.6 -90)
		(descr "Capacitor SMD 0402")
		(tags "capacitor SMD 0402")
		(property "Reference" "C119"
			(at 0 -0.699 270)
			(layer "F.SilkS")
			(hide yes)
			(effects
				(font
					(size 0.7 0.7)
					(thickness 0.15)
				)
				(justify left bottom)
			)
		)
		(property "Value" "C_100n_0402"
			(at -1.022927 2.155213 270)
			(layer "F.Fab")
			(effects
				(font
					(size 0.7 0.7)
					(thickness 0.15)
				)
				(justify left bottom)
			)
		)
		(property "Datasheet" "https://www.murata.com/products/productdetail?partno=GRM155R61H104KE14%23"
			(at 0 0 270)
			(layer "F.Fab")
			(hide yes)
			(effects
				(font
					(size 1.27 1.27)
					(thickness 0.15)
				)
			)
		)
		(property "Author" "Antmicro"
			(at -82.7 278.5 0)
			(layer "F.Fab")
			(hide yes)
			(effects
				(font
					(size 1 1)
					(thickness 0.15)
				)
			)
		)
		(property "Dielectric" "X5R"
			(at -82.7 278.5 0)
			(layer "F.Fab")
			(hide yes)
			(effects
				(font
					(size 1 1)
					(thickness 0.15)
				)
			)
		)
		(property "License" "Apache-2.0"
			(at -82.7 278.5 0)
			(layer "F.Fab")
			(hide yes)
			(effects
				(font
					(size 1 1)
					(thickness 0.15)
				)
			)
		)
		(property "MPN" "GRM155R61H104KE14D"
			(at -82.7 278.5 0)
			(layer "F.Fab")
			(hide yes)
			(effects
				(font
					(size 1 1)
					(thickness 0.15)
				)
			)
		)
		(property "Manufacturer" "Murata"
			(at -82.7 278.5 0)
			(layer "F.Fab")
			(hide yes)
			(effects
				(font
					(size 1 1)
					(thickness 0.15)
				)
			)
		)
		(property "Val" "100n"
			(at -82.7 278.5 0)
			(layer "F.Fab")
			(hide yes)
			(effects
				(font
					(size 1 1)
					(thickness 0.15)
				)
			)
		)
		(property "Voltage" "50V"
			(at -82.7 278.5 0)
			(layer "F.Fab")
			(hide yes)
			(effects
				(font
					(size 1 1)
					(thickness 0.15)
				)
			)
		)
		(sheetname "/Debug FTDI/")
		(sheetfile "debug-ftdi.kicad_sch")
		(attr smd)
		(fp_rect
			(start -0.9659 -0.481258)
			(end 0.9649 0.458742)
			(stroke
				(width 0.05)
				(type solid)
			)
			(fill no)
			(layer "F.CrtYd")
		)
		(fp_line
			(start -0.499 0.248)
			(end -0.499 -0.25)
			(stroke
				(width 0.15)
				(type solid)
			)
			(layer "F.Fab")
		)
		(fp_line
			(start 0.499 0.248)
			(end -0.499 0.248)
			(stroke
				(width 0.15)
				(type solid)
			)
			(layer "F.Fab")
		)
		(fp_line
			(start -0.499 -0.25)
			(end 0.499 -0.25)
			(stroke
				(width 0.15)
				(type solid)
			)
			(layer "F.Fab")
		)
		(fp_line
			(start 0.499 -0.25)
			(end 0.499 0.248)
			(stroke
				(width 0.15)
				(type solid)
			)
			(layer "F.Fab")
		)
		(pad "1" smd roundrect
			(at -0.484 0 270)
			(size 0.59 0.64)
			(layers "F.Cu" "F.Mask" "F.Paste")
			(roundrect_rratio 0.25)
			(net 6 "/Debug FTDI/FTDI_3V3")
			(pintype "passive")
		)
		(pad "2" smd roundrect
			(at 0.484 0 270)
			(size 0.59 0.64)
			(layers "F.Cu" "F.Mask" "F.Paste")
			(roundrect_rratio 0.25)
			(net 1 "GND")
			(pintype "passive")
		)
	)
)
